FILE_TYPE = MULTI_PHYS_TABLE;

PART 'LCMXO3LF9400C5BG484C'

{========================================================================================}
:VALUE                    | PART_TYPE | MATERIAL | PART_NUMBER    = STANDARD        | LIFECYCLE     | PART_NUMBER   | JEDEC_TYPE             | DESCRIPTION                             | MANUFTR | MANUF_PN                 | RD_CMPLS_LVL | CMPLS_LVL | FROM_PJ      | CLASS | DIP_SMD | DATA                             | EE_CHECK_LIST | FP_ECN | PSL | CREATOR | STATUS | MSD | ESD_CDM | ESD_HBM | ESD_MM | PIN_LENGTH_SHORT_PIN | PIN_LENGTH_LONG_PIN | CREATEDAY  ;
{========================================================================================}
 'LCMXO3LF-9400C-5BG484C' | 'SMLF'    | 'IC'     | 'AJ094000T08'(!) = ''               | ''               | 'AJ094000T08' |'BGA484_0-8_19X19_H67'| 'IC(484P)LCMXO3LF-9400C-5BG484C(CABGA)' | 'LSC'   | 'LCMXO3LF-9400C-5BG484C' | 'EP(V1)'     | ''        | 'F0T-FENTUS' | 'IC'  | ''      | 'LSC_LCMXO3LF-9400C-5BG484C.pdf' | ''            | ''     | ''  | ''      | ''     | ''  | ''      | ''      | ''     | '0 MILS'             | '0 MILS'            | '20210929'
 'LCMXO3LF-9400C-5BG484C' | 'SMLF'    | 'EMPTY'  | 'AJ094000T08'(!) = ''               | ''               | 'AJ094000T08' |'BGA484_0-8_19X19_H67'| 'IC(484P)LCMXO3LF-9400C-5BG484C(CABGA)' | 'LSC'   | 'LCMXO3LF-9400C-5BG484C' | 'EP(V1)'     | ''        | 'F0T-FENTUS' | 'IC'  | ''      | 'LSC_LCMXO3LF-9400C-5BG484C.pdf' | ''            | ''     | ''  | ''      | ''     | ''  | ''      | ''      | ''     | '0 MILS'             | '0 MILS'            | '20210929'

END_PART

END.

